(kicad_pcb
	(version 20260206)
	(generator "pcbnew")
	(generator_version "10.0")
	(general
		(thickness 1.6)
		(legacy_teardrops no)
	)
	(paper "A4")
	(title_block
		(title "Bryce Canyon_SCC_16316-1_OCP.brd")
		(comment 1 "Bryce Canyon / footprints 406-413 of 1561")
	)
	(layers
		(0 "F.Cu" signal "TOP")
		(4 "In1.Cu" signal "L2GND")
		(6 "In2.Cu" signal "L3")
		(8 "In3.Cu" signal "L4VCC")
		(10 "In4.Cu" signal "L5VCC")
		(12 "In5.Cu" signal "L6")
		(14 "In6.Cu" signal "L7GND")
		(2 "B.Cu" signal "BOTTOM")
		(9 "F.Adhes" user "F.Adhesive")
		(11 "B.Adhes" user "B.Adhesive")
		(13 "F.Paste" user "Package Geometry/Pastemask Top")
		(15 "B.Paste" user "Package Geometry/Pastemask Bottom")
		(5 "F.SilkS" user "Ref Des/Silkscreen Top")
		(7 "B.SilkS" user "Ref Des/Silkscreen Bottom")
		(1 "F.Mask" user "Board Geometry/Soldermask Top")
		(3 "B.Mask" user "Board Geometry/Soldermask Bottom")
		(17 "Dwgs.User" user "User.Drawings")
		(19 "Cmts.User" user "User.Comments")
		(21 "Eco1.User" user "User.Eco1")
		(23 "Eco2.User" user "User.Eco2")
		(25 "Edge.Cuts" user "Board Geometry/Outline")
		(27 "Margin" user)
		(31 "F.CrtYd" user "Package Geometry/Place Bound Top")
		(29 "B.CrtYd" user "Package Geometry/Place Bound Bottom")
		(35 "F.Fab" user "Ref Des/Assembly Top")
		(33 "B.Fab" user "Ref Des/Assembly Bottom")
	)
	(footprint ""
		(layer "F.Cu")
		(at 85.8266 -108.204 180)
		(property "Reference" "C731"
			(at 0 0 180)
			(layer "F.SilkS")
			(hide yes)
			(effects
				(font
					(size 1.27 1.27)
				)
			)
		)
		(property "Value" "SCD1U16V2KX-3GP"
			(at 1.1811 -2.7051 180)
			(unlocked yes)
			(layer "F.Fab")
			(hide yes)
			(effects
				(font
					(size 1.016 1.016)
					(thickness 0.1524)
				)
			)
		)
		(property "Device Type" "C402H22"
			(at 1.1811 -4.2291 180)
			(unlocked yes)
			(layer "F.Fab")
			(hide yes)
			(effects
				(font
					(size 1.016 1.016)
					(thickness 0.1524)
				)
			)
		)
		(duplicate_pad_numbers_are_jumpers no)
		(fp_rect
			(start -0.4318 0.9525)
			(end 0.4318 -0.9525)
			(stroke
				(width 0)
				(type default)
			)
			(fill no)
			(layer "F.CrtYd")
		)
		(fp_rect
			(start -0.4318 0.9525)
			(end 0.4318 -0.9525)
			(stroke
				(width 0)
				(type default)
			)
			(fill no)
			(layer "F.Fab")
		)
		(pad "1" smd custom
			(at 0 -0.4445 180)
			(size 0.1524 0.1524)
			(layers "F.Cu" "F.Mask" "F.Paste")
			(net "P3V3")
			(options
				(clearance outline)
				(anchor circle)
			)
			(primitives
				(gr_poly
					(pts
						(arc
							(start 0.3048 -0.2032)
							(mid 0.275042 -0.275042)
							(end 0.2032 -0.3048)
						)
						(arc
							(start -0.2032 -0.3048)
							(mid -0.275042 -0.275042)
							(end -0.3048 -0.2032)
						)
						(arc
							(start -0.3048 0.2032)
							(mid -0.275042 0.275042)
							(end -0.2032 0.3048)
						)
						(arc
							(start 0.2032 0.3048)
							(mid 0.275042 0.275042)
							(end 0.3048 0.2032)
						)
					)
					(width 0)
					(fill yes)
				)
			)
		)
		(pad "2" smd custom
			(at 0 0.4445 180)
			(size 0.1524 0.1524)
			(layers "F.Cu" "F.Mask" "F.Paste")
			(net "GND")
			(options
				(clearance outline)
				(anchor circle)
			)
			(primitives
				(gr_poly
					(pts
						(arc
							(start 0.3048 -0.2032)
							(mid 0.275042 -0.275042)
							(end 0.2032 -0.3048)
						)
						(arc
							(start -0.2032 -0.3048)
							(mid -0.275042 -0.275042)
							(end -0.3048 -0.2032)
						)
						(arc
							(start -0.3048 0.2032)
							(mid -0.275042 0.275042)
							(end -0.2032 0.3048)
						)
						(arc
							(start 0.2032 0.3048)
							(mid 0.275042 0.275042)
							(end 0.3048 0.2032)
						)
					)
					(width 0)
					(fill yes)
				)
			)
		)
	)
	(footprint ""
		(layer "F.Cu")
		(at 168.732454 -8.52551 180)
		(property "Reference" "R80"
			(at 0 0 180)
			(layer "F.SilkS")
			(hide yes)
			(effects
				(font
					(size 1.27 1.27)
				)
			)
		)
		(property "Value" "0R2J-2-GP"
			(at 0.064008 -3.993896 180)
			(unlocked yes)
			(layer "F.Fab")
			(hide yes)
			(effects
				(font
					(size 1.016 1.016)
					(thickness 0.1524)
				)
			)
		)
		(property "Device Type" "R402H16"
			(at 0.064008 -5.517896 180)
			(unlocked yes)
			(layer "F.Fab")
			(hide yes)
			(effects
				(font
					(size 1.016 1.016)
					(thickness 0.1524)
				)
			)
		)
		(duplicate_pad_numbers_are_jumpers no)
		(fp_line
			(start 0.508 -0.9398)
			(end -0.508 -0.9398)
			(stroke
				(width 0.1524)
				(type default)
			)
			(layer "F.SilkS")
		)
		(fp_line
			(start -0.508 -0.9398)
			(end -0.508 0.9398)
			(stroke
				(width 0.1524)
				(type default)
			)
			(layer "F.SilkS")
		)
		(fp_rect
			(start -0.508 0.9398)
			(end 0.508 -0.9398)
			(stroke
				(width 0)
				(type default)
			)
			(fill no)
			(layer "F.CrtYd")
		)
		(fp_rect
			(start -0.508 0.9398)
			(end 0.508 -0.9398)
			(stroke
				(width 0)
				(type default)
			)
			(fill no)
			(layer "F.Fab")
		)
		(pad "1" smd custom
			(at 0 -0.4445 180)
			(size 0.1397 0.1397)
			(layers "F.Cu" "F.Mask" "F.Paste")
			(net "LS_EN_U12")
			(options
				(clearance outline)
				(anchor circle)
			)
			(primitives
				(gr_poly
					(pts
						(arc
							(start -0.1778 -0.2794)
							(mid -0.249642 -0.249642)
							(end -0.2794 -0.1778)
						)
						(arc
							(start -0.2794 0.1778)
							(mid -0.249642 0.249642)
							(end -0.1778 0.2794)
						)
						(arc
							(start 0.1778 0.2794)
							(mid 0.249642 0.249642)
							(end 0.2794 0.1778)
						)
						(arc
							(start 0.2794 -0.1778)
							(mid 0.249642 -0.249642)
							(end 0.1778 -0.2794)
						)
					)
					(width 0)
					(fill yes)
				)
			)
		)
		(pad "2" smd custom
			(at 0 0.4445 180)
			(size 0.1397 0.1397)
			(layers "F.Cu" "F.Mask" "F.Paste")
			(net "LS_EN_N")
			(options
				(clearance outline)
				(anchor circle)
			)
			(primitives
				(gr_poly
					(pts
						(arc
							(start -0.1778 -0.2794)
							(mid -0.249642 -0.249642)
							(end -0.2794 -0.1778)
						)
						(arc
							(start -0.2794 0.1778)
							(mid -0.249642 0.249642)
							(end -0.1778 0.2794)
						)
						(arc
							(start 0.1778 0.2794)
							(mid 0.249642 0.249642)
							(end 0.2794 0.1778)
						)
						(arc
							(start 0.2794 -0.1778)
							(mid 0.249642 -0.249642)
							(end 0.1778 -0.2794)
						)
					)
					(width 0)
					(fill yes)
				)
			)
		)
	)
	(footprint ""
		(layer "F.Cu")
		(at 176.86147 -82.652108)
		(property "Reference" "C630"
			(at 0 0 0)
			(layer "F.SilkS")
			(hide yes)
			(effects
				(font
					(size 1.27 1.27)
				)
			)
		)
		(property "Value" "SC10U6D3V5KX-4GP"
			(at -0.0762 -6.1214 0)
			(unlocked yes)
			(layer "F.Fab")
			(hide yes)
			(effects
				(font
					(size 1.016 1.016)
					(thickness 0.1524)
				)
			)
		)
		(property "Device Type" "C805H58"
			(at -0.0762 -8.1534 0)
			(unlocked yes)
			(layer "F.Fab")
			(hide yes)
			(effects
				(font
					(size 1.016 1.016)
					(thickness 0.1524)
				)
			)
		)
		(duplicate_pad_numbers_are_jumpers no)
		(fp_line
			(start 0.635 0)
			(end -0.635 0)
			(stroke
				(width 0.508)
				(type default)
			)
			(layer "F.SilkS")
		)
		(fp_rect
			(start -0.9652 1.778)
			(end 0.9652 -1.778)
			(stroke
				(width 0)
				(type default)
			)
			(fill no)
			(layer "F.CrtYd")
		)
		(fp_poly
			(pts
				(xy -0.9652 -1.778) (xy 0.9652 -1.778) (xy 0.9652 1.778) (xy -0.9652 1.778)
			)
			(stroke
				(width 0)
				(type default)
			)
			(fill no)
			(layer "F.Fab")
		)
		(pad "1" smd rect
			(at 0 -0.9652)
			(size 1.397 1.143)
			(layers "F.Cu" "F.Mask" "F.Paste")
			(net "P0V975")
		)
		(pad "2" smd rect
			(at 0 0.9652)
			(size 1.397 1.143)
			(layers "F.Cu" "F.Mask" "F.Paste")
			(net "GND")
		)
	)
	(footprint ""
		(layer "F.Cu")
		(at 145.669 -100.584 180)
		(property "Reference" "C720"
			(at 0 0 180)
			(layer "F.SilkS")
			(hide yes)
			(effects
				(font
					(size 1.27 1.27)
				)
			)
		)
		(property "Value" "SC100U6D3V6MX-GP"
			(at -0.0762 -5.1308 180)
			(unlocked yes)
			(layer "F.Fab")
			(hide yes)
			(effects
				(font
					(size 1.016 1.016)
					(thickness 0.1524)
				)
			)
		)
		(property "Device Type" "C1206H71"
			(at -0.127 -6.6548 180)
			(unlocked yes)
			(layer "F.Fab")
			(hide yes)
			(effects
				(font
					(size 1.016 1.016)
					(thickness 0.1524)
				)
			)
		)
		(duplicate_pad_numbers_are_jumpers no)
		(fp_line
			(start 1.016 2.2352)
			(end -1.016 2.2352)
			(stroke
				(width 0.1524)
				(type default)
			)
			(layer "F.SilkS")
		)
		(fp_line
			(start 1.016 0.8382)
			(end 1.016 2.2352)
			(stroke
				(width 0.1524)
				(type default)
			)
			(layer "F.SilkS")
		)
		(fp_line
			(start 1.016 -2.2352)
			(end 1.016 -0.8382)
			(stroke
				(width 0.1524)
				(type default)
			)
			(layer "F.SilkS")
		)
		(fp_line
			(start -1.016 2.2352)
			(end -1.016 0.8382)
			(stroke
				(width 0.1524)
				(type default)
			)
			(layer "F.SilkS")
		)
		(fp_line
			(start -1.016 -0.8382)
			(end -1.016 -2.2352)
			(stroke
				(width 0.1524)
				(type default)
			)
			(layer "F.SilkS")
		)
		(fp_line
			(start -1.016 -2.2352)
			(end 1.016 -2.2352)
			(stroke
				(width 0.1524)
				(type default)
			)
			(layer "F.SilkS")
		)
		(fp_rect
			(start -1.0922 2.3114)
			(end 1.0922 -2.3114)
			(stroke
				(width 0)
				(type default)
			)
			(fill no)
			(layer "F.CrtYd")
		)
		(fp_poly
			(pts
				(xy 1.0922 -2.3114) (xy 1.0922 2.3114) (xy -1.0922 2.3114) (xy -1.0922 -2.3114)
			)
			(stroke
				(width 0)
				(type default)
			)
			(fill no)
			(layer "F.Fab")
		)
		(pad "1" smd rect
			(at 0 -1.397 180)
			(size 1.651 1.27)
			(layers "F.Cu" "F.Mask" "F.Paste")
			(net "GB_VDDH")
		)
		(pad "2" smd rect
			(at 0 1.397 180)
			(size 1.651 1.27)
			(layers "F.Cu" "F.Mask" "F.Paste")
			(net "GND")
		)
	)
	(footprint ""
		(layer "F.Cu")
		(at 191.516 -27.8384 -90)
		(property "Reference" "TP59"
			(at 0 0 270)
			(layer "F.SilkS")
			(hide yes)
			(effects
				(font
					(size 1.27 1.27)
				)
			)
		)
		(property "Value" "TPAD28-2-GP"
			(at -0.0127 -1.6637 270)
			(unlocked yes)
			(layer "F.Fab")
			(hide yes)
			(effects
				(font
					(size 1.016 1.016)
					(thickness 0.1524)
				)
			)
		)
		(property "Device Type" "TPAD28"
			(at -0.0127 -3.1877 270)
			(unlocked yes)
			(layer "F.Fab")
			(hide yes)
			(effects
				(font
					(size 1.016 1.016)
					(thickness 0.1524)
				)
			)
		)
		(duplicate_pad_numbers_are_jumpers no)
		(fp_poly
			(pts
				(arc
					(start 0 -0.3556)
					(mid 0 0.3556)
					(end 0 -0.3556)
				)
			)
			(stroke
				(width 0)
				(type default)
			)
			(fill no)
			(layer "F.CrtYd")
		)
		(fp_poly
			(pts
				(arc
					(start 0 -0.6096)
					(mid 0 0.6096)
					(end 0 -0.6096)
				)
			)
			(stroke
				(width 0)
				(type default)
			)
			(fill no)
			(layer "F.Fab")
		)
		(pad "1" smd circle
			(at 0 0 270)
			(size 0.7112 0.7112)
			(layers "F.Cu" "F.Mask" "F.Paste")
			(net "IOC_GPIO_4")
		)
	)
	(footprint ""
		(layer "F.Cu")
		(at 45.5422 -29.083 -90)
		(property "Reference" "C612"
			(at 0 0 270)
			(layer "F.SilkS")
			(hide yes)
			(effects
				(font
					(size 1.27 1.27)
				)
			)
		)
		(property "Value" "SCD01U25V2KX-3GP"
			(at 1.1811 -2.7051 270)
			(unlocked yes)
			(layer "F.Fab")
			(hide yes)
			(effects
				(font
					(size 1.016 1.016)
					(thickness 0.1524)
				)
			)
		)
		(property "Device Type" "C402H22"
			(at 1.1811 -4.2291 270)
			(unlocked yes)
			(layer "F.Fab")
			(hide yes)
			(effects
				(font
					(size 1.016 1.016)
					(thickness 0.1524)
				)
			)
		)
		(duplicate_pad_numbers_are_jumpers no)
		(fp_rect
			(start -0.4318 0.9525)
			(end 0.4318 -0.9525)
			(stroke
				(width 0)
				(type default)
			)
			(fill no)
			(layer "F.CrtYd")
		)
		(fp_rect
			(start -0.4318 0.9525)
			(end 0.4318 -0.9525)
			(stroke
				(width 0)
				(type default)
			)
			(fill no)
			(layer "F.Fab")
		)
		(pad "1" smd custom
			(at 0 -0.4445 270)
			(size 0.1524 0.1524)
			(layers "F.Cu" "F.Mask" "F.Paste")
			(net "P0V9_GSNS")
			(options
				(clearance outline)
				(anchor circle)
			)
			(primitives
				(gr_poly
					(pts
						(arc
							(start 0.3048 -0.2032)
							(mid 0.275042 -0.275042)
							(end 0.2032 -0.3048)
						)
						(arc
							(start -0.2032 -0.3048)
							(mid -0.275042 -0.275042)
							(end -0.3048 -0.2032)
						)
						(arc
							(start -0.3048 0.2032)
							(mid -0.275042 0.275042)
							(end -0.2032 0.3048)
						)
						(arc
							(start 0.2032 0.3048)
							(mid 0.275042 0.275042)
							(end 0.3048 0.2032)
						)
					)
					(width 0)
					(fill yes)
				)
			)
		)
		(pad "2" smd custom
			(at 0 0.4445 270)
			(size 0.1524 0.1524)
			(layers "F.Cu" "F.Mask" "F.Paste")
			(net "P0V9_REFIN")
			(options
				(clearance outline)
				(anchor circle)
			)
			(primitives
				(gr_poly
					(pts
						(arc
							(start 0.3048 -0.2032)
							(mid 0.275042 -0.275042)
							(end 0.2032 -0.3048)
						)
						(arc
							(start -0.2032 -0.3048)
							(mid -0.275042 -0.275042)
							(end -0.3048 -0.2032)
						)
						(arc
							(start -0.3048 0.2032)
							(mid -0.275042 0.275042)
							(end -0.2032 0.3048)
						)
						(arc
							(start 0.2032 0.3048)
							(mid 0.275042 0.275042)
							(end 0.3048 0.2032)
						)
					)
					(width 0)
					(fill yes)
				)
			)
		)
	)
	(footprint ""
		(layer "F.Cu")
		(at 54.9148 -80.518 90)
		(property "Reference" "C561"
			(at 0 0 90)
			(layer "F.SilkS")
			(hide yes)
			(effects
				(font
					(size 1.27 1.27)
				)
			)
		)
		(property "Value" "SCD1U16V2KX-3GP"
			(at 1.1811 -2.7051 90)
			(unlocked yes)
			(layer "F.Fab")
			(hide yes)
			(effects
				(font
					(size 1.016 1.016)
					(thickness 0.1524)
				)
			)
		)
		(property "Device Type" "C402H22"
			(at 1.1811 -4.2291 90)
			(unlocked yes)
			(layer "F.Fab")
			(hide yes)
			(effects
				(font
					(size 1.016 1.016)
					(thickness 0.1524)
				)
			)
		)
		(duplicate_pad_numbers_are_jumpers no)
		(fp_rect
			(start -0.4318 0.9525)
			(end 0.4318 -0.9525)
			(stroke
				(width 0)
				(type default)
			)
			(fill no)
			(layer "F.CrtYd")
		)
		(fp_rect
			(start -0.4318 0.9525)
			(end 0.4318 -0.9525)
			(stroke
				(width 0)
				(type default)
			)
			(fill no)
			(layer "F.Fab")
		)
		(pad "1" smd custom
			(at 0 -0.4445 90)
			(size 0.1524 0.1524)
			(layers "F.Cu" "F.Mask" "F.Paste")
			(net "P1V8_E")
			(options
				(clearance outline)
				(anchor circle)
			)
			(primitives
				(gr_poly
					(pts
						(arc
							(start 0.3048 -0.2032)
							(mid 0.275042 -0.275042)
							(end 0.2032 -0.3048)
						)
						(arc
							(start -0.2032 -0.3048)
							(mid -0.275042 -0.275042)
							(end -0.3048 -0.2032)
						)
						(arc
							(start -0.3048 0.2032)
							(mid -0.275042 0.275042)
							(end -0.2032 0.3048)
						)
						(arc
							(start 0.2032 0.3048)
							(mid 0.275042 0.275042)
							(end 0.3048 0.2032)
						)
					)
					(width 0)
					(fill yes)
				)
			)
		)
		(pad "2" smd custom
			(at 0 0.4445 90)
			(size 0.1524 0.1524)
			(layers "F.Cu" "F.Mask" "F.Paste")
			(net "GND")
			(options
				(clearance outline)
				(anchor circle)
			)
			(primitives
				(gr_poly
					(pts
						(arc
							(start 0.3048 -0.2032)
							(mid 0.275042 -0.275042)
							(end 0.2032 -0.3048)
						)
						(arc
							(start -0.2032 -0.3048)
							(mid -0.275042 -0.275042)
							(end -0.3048 -0.2032)
						)
						(arc
							(start -0.3048 0.2032)
							(mid -0.275042 0.275042)
							(end -0.2032 0.3048)
						)
						(arc
							(start 0.2032 0.3048)
							(mid 0.275042 0.275042)
							(end 0.3048 0.2032)
						)
					)
					(width 0)
					(fill yes)
				)
			)
		)
	)
	(footprint ""
		(layer "F.Cu")
		(at 134.52221 -84.246466 -90)
		(property "Reference" "R60"
			(at 0 0 270)
			(layer "F.SilkS")
			(hide yes)
			(effects
				(font
					(size 1.27 1.27)
				)
			)
		)
		(property "Value" "4K7R2F-GP"
			(at 0.064008 -3.993896 270)
			(unlocked yes)
			(layer "F.Fab")
			(hide yes)
			(effects
				(font
					(size 1.016 1.016)
					(thickness 0.1524)
				)
			)
		)
		(property "Device Type" "R402H16"
			(at 0.064008 -5.517896 270)
			(unlocked yes)
			(layer "F.Fab")
			(hide yes)
			(effects
				(font
					(size 1.016 1.016)
					(thickness 0.1524)
				)
			)
		)
		(duplicate_pad_numbers_are_jumpers no)
		(fp_line
			(start -0.508 -0.9398)
			(end -0.508 0.9398)
			(stroke
				(width 0.1524)
				(type default)
			)
			(layer "F.SilkS")
		)
		(fp_line
			(start 0.508 -0.9398)
			(end -0.508 -0.9398)
			(stroke
				(width 0.1524)
				(type default)
			)
			(layer "F.SilkS")
		)
		(fp_rect
			(start -0.508 0.9398)
			(end 0.508 -0.9398)
			(stroke
				(width 0)
				(type default)
			)
			(fill no)
			(layer "F.CrtYd")
		)
		(fp_rect
			(start -0.508 0.9398)
			(end 0.508 -0.9398)
			(stroke
				(width 0)
				(type default)
			)
			(fill no)
			(layer "F.Fab")
		)
		(pad "1" smd custom
			(at 0 -0.4445 270)
			(size 0.1397 0.1397)
			(layers "F.Cu" "F.Mask" "F.Paste")
			(net "P1V8_E")
			(options
				(clearance outline)
				(anchor circle)
			)
			(primitives
				(gr_poly
					(pts
						(arc
							(start -0.1778 -0.2794)
							(mid -0.249642 -0.249642)
							(end -0.2794 -0.1778)
						)
						(arc
							(start -0.2794 0.1778)
							(mid -0.249642 0.249642)
							(end -0.1778 0.2794)
						)
						(arc
							(start 0.1778 0.2794)
							(mid 0.249642 0.249642)
							(end 0.2794 0.1778)
						)
						(arc
							(start 0.2794 -0.1778)
							(mid 0.249642 -0.249642)
							(end 0.1778 -0.2794)
						)
					)
					(width 0)
					(fill yes)
				)
			)
		)
		(pad "2" smd custom
			(at 0 0.4445 270)
			(size 0.1397 0.1397)
			(layers "F.Cu" "F.Mask" "F.Paste")
			(net "I2C_DRIVE_FLT_LED_SCL6_LS")
			(options
				(clearance outline)
				(anchor circle)
			)
			(primitives
				(gr_poly
					(pts
						(arc
							(start -0.1778 -0.2794)
							(mid -0.249642 -0.249642)
							(end -0.2794 -0.1778)
						)
						(arc
							(start -0.2794 0.1778)
							(mid -0.249642 0.249642)
							(end -0.1778 0.2794)
						)
						(arc
							(start 0.1778 0.2794)
							(mid 0.249642 0.249642)
							(end 0.2794 0.1778)
						)
						(arc
							(start 0.2794 -0.1778)
							(mid 0.249642 -0.249642)
							(end 0.1778 -0.2794)
						)
					)
					(width 0)
					(fill yes)
				)
			)
		)
	)
)
